FILE_TYPE = CONNECTIVITY;
{Allegro Design Entry HDL 16.6-p007 (v16-6-112F) 10/10/2012}
"PAGE_NUMBER" = 146;
0"NC";
1"LPC_LAD_IO<3:0>";
2"GND\g";
3"P3V3_STBY\g";
4"GND\g";
5"GND\g";
6"GND\g";
7"IRQ_PCH_NIC_ALERT_N";
8"FM_BIOS_POST_CMPLT_N";
9"FM_BMC_NMI_N_R";
10"FM_BMC_SYS_THROTTLE_R_N";
11"FM_CPU1_PROC_ID1";
12"IRQ_SML1_PMBUS_ALERT_N";
13"IRQ_OOB_MGMT_RISER_ALERT_N";
14"H_CPU0_MEMABC_MEMHOT_LVT3_BMC_N";
15"IRQ_BMC_PCH_SCI_LPC_N";
16"PD_SP_ENTEST";
17"SPI_BMC_BT_CS1_N";
18"SPI_BMC_CS0_N";
19"SPI_BMC_CLK";
20"SPI_BMC_DO";
21"SPI_BMC_DI";
22"FM_PE_BMC_WAKE_N";
23"FM_CPU0_FIVR_FAULT_LVT3_R_N";
24"FM_CPU1_THERMTRIP_LATCH_LVT3_N";
25"FM_CPU0_FIVR_FAULT_LVT3_N";
26"BMC_M_MALERT_N";
27"BMC_M_RST_N";
28"CLK_24M_BMC_LPC_R1";
29"LPC_LFRAME_N_CS0_R_N";
30"IRQ_LPC_SERIRQ_R";
31"RST_BMC_LVC3_N";
32"SPI_BMC_BT_DO_R";
33"FM_THROTTLE_N";
34"FM_BMC_READY_N";
35"IRQ_MEZZ_LAN_ALERT_N"$PHYS_NET_NAME"IRQ_MEZZ_LAN_ALERT_N"CDS_PHYS_NET_NAME"IRQ_MEZZ_LAN_ALERT_N";
36"IRQ_LOM_ALERT_N";
37"H_CPU0_MEMDEF_MEMHOT_LVT3_BMC_N";
38"IRQ_FORCE_NM_THROTTLE_N"CDS_PHYS_NET_NAME"IRQ_FORCE_NM_THROTTLE_N";
39"LPC_LAD0_IO0_R";
40"LPC_LAD2_IO2_R";
41"TP_DDCCLK_GPIOJ6";
42"TP_DDCDAT_GPIOJ7";
43"SPI_BMC_BT_CLK_R";
44"SPI_BMC_BT_CS_R_N";
45"TP_VGAVS_GPIOJ5";
46"TP_VGAHS_GPIOJ4";
47"LED_POSTCODE_3";
48"LED_POSTCODE_4";
49"LED_POSTCODE_5";
50"FM_BMC_NMI_N";
51"IRQ_SML0_ALERT_N";
52"GPIOS7";
53"FP_PWR_ID_LED_N";
54"FM_SPEAKER_PCH_N";
55"FM_CPU1_PROC_ID0";
56"FM_CPU0_THERMTRIP_LATCH_LVT3_N";
57"SPI_BMC_BT_DO";
58"SPI_BMC_BT_DI";
59"SPI_BMC_BT_CLK";
60"LED_POSTCODE_1";
61"LED_POSTCODE_0";
62"USB2_PCH_BMC_P5_DN";
63"HSC_SMBUS_SWITCH_EN";
64"FM_BIOS_SPI_BMC_CTRL";
65"LPC_LAD_IO<3>";
66"LPC_LAD_IO<2>";
67"LPC_LAD_IO<1>";
68"LPC_LAD_IO<0>";
69"CLK_24M_BMC_LPC";
70"IRQ_LPC_SERIRQ_N";
71"SPI_BMC_BT_CS_N";
72"LPC_LFRAME_N_CS0_N";
73"RST_PLTRST_BUF_N";
74"USB_PCH_BMC_P4_DP";
75"A_USB2AVRES";
76"USB_PCH_BMC_P4_DN";
77"USB2_PCH_BMC_P5_DP";
78"A_USB2BVRES";
79"LED_POSTCODE_7";
80"LED_POSTCODE_6";
81"LPC_LAD1_IO1_R";
82"LPC_LAD3_IO3_R";
83"LED_POSTCODE_2";
%"AST2520A1-GP-GP"
"4","(-3875,4000)","0","w_hdl","I104";
;
CDS_SEC"4"
$SEC"4"
CDS_LOCATION"U25W4"
CDS_LMAN_SYM_OUTLINE"-1350,800,1350,-800"
CDS_LIB"w_hdl"
PACK_TYPE"ASIC2-GB1"
PART_NUMBER"071.2520A.M001"
VALUE"AST2520A1-GP-GP"
LOCATION"U25W4";
"GPIOAA3_VPOR5_NORD3_SALT10"
$PN"AA22"0;
"GPIOAA4_VPOR6_NORD4_SALT11"
$PN"U22"0;
"GPIOAA5_VPOR7_NORD5_SALT12"
$PN"T20"7;
"GPIOAA6_VPOR8_NORD6_SALT13"
$PN"N18"0;
"GPIOAA7_VPOR9_NORD7_SALT14"
$PN"P19"8;
"GPIOAA1_VPOR3_NORD1_SALT8"
$PN"V21"12;
"GPIOS1_VPOB3_BMCINT"
$PN"U19"34;
"GPIOS4_VPOB6"
$PN"R19"37;
"GPIOS5_VPOB7"
$PN"W20"54;
"GPIOS6_VPOB8"
$PN"U20"53;
"USB2B_DN"
$PN"A6"76;
"USB2B_DP"
$PN"B6"74;
"USB2A_DN"
$PN"A8"62;
"USB2A_DP"
$PN"A7"77;
"GPIOAA2_VPOR4_NORD2_SALT9"
$PN"Y22"13;
"GPIOZ0_VPOG2_NORA0_SIOPBI# \B"
$PN"Y20"64;
"GPIOS7_VPOB9"
$PN"AA20"52;
"GPIOS3_VPOB5_SALT6"
$PN"P18"36;
"GPIOAA0_VPOR2_NORD0_SALT7"
$PN"Y21"11;
"GPIOZ7_VPOG9_NORA7"
$PN"W21"55;
"GPIOZ6_VPOG8_NORA6"
$PN"V22"14;
"GPIOZ5_VPOG7_NORA5"
$PN"W22"56;
"GPIOZ4_VPOG6_NORA4"
$PN"U21"63;
"GPIOZ3_VPOG5_NORA3_SIOSCI# \B"
$PN"AA21"15;
"GPIOZ2_VPOG4_NORA2_SIOPBO# \B"
$PN"AB21"10;
"GPIOZ1_VPOG3_NORA1_SIOPWRGD"
$PN"AB20"9;
"GPIOS2_VPOB4_SALT5"
$PN"R18"35;
"GPIOS0_VPOB2_SPI2CS1# \B"
$PN"V20"33;
"GPIOH6_TXD6"
$PN"A16"80;
"GPIOH7_RXD6"
$PN"D18"79;
"GPIOH5_NRTS6"
$PN"B17"49;
"GPIOH3_NRI6"
$PN"C17"47;
"GPIOH4_NDTR6"
$PN"A17"48;
"GPIOH1_NDCD6"
$PN"B18"60;
"GPIOH2_NDSR6"
$PN"D17"83;
"GPIOH0_NCTS6"
$PN"A18"61;
"USB2AVRES"
$PN"B8"75;
"USB2BVRES"
$PN"B7"78;
%"AST2520A1-GP-GP"
"5","(-4100,1850)","0","w_hdl","I105";
;
CDS_SEC"5"
$SEC"5"
CDS_LOCATION"U25W4"
CDS_LIB"w_hdl"
PART_NUMBER"071.2520A.M001"
PACK_TYPE"ASIC2-GB1"
CDS_LMAN_SYM_OUTLINE"-1325,950,1325,-950"
LOCATION"U25W4"
VALUE"AST2520A1-GP-GP";
"GPIOR4_SPI2MOSI"
$PN"W19"20;
"GPIOR3_SPI2CK"
$PN"Y19"19;
"GPIOAC5_ESPICS#_LFRAME# \B"
$PN"F21"29;
"GPIOAC6_ESPIALT#_LSIRQ# \B"
$PN"F22"30;
"FWSPICS0# \B"
$PN"AB19"44;
"FWSPIMISO"
$PN"T18"58;
"GPIOAC0_ESPID0_LAD0"
$PN"G21"39;
"GPIOAC1_ESPID1_LAD1"
$PN"G20"81;
"GPIOAC2_ESPID2_LAD2"
$PN"D22"40;
"GPIOAC3_ESPID3_LAD3"
$PN"E22"82;
"GPIOAC4_ESPICK_LCLK"
$PN"C22"28;
"GPIOAB0_VPODE_NOROE# \B"
$PN"N19"0;
"GPIOAB1_VPOHS_NORWE# \B"
$PN"T21"0;
"GPIOAB2_VPOVS_WDTRST1"
$PN"T22"0;
"GPIOAB3_VPOCLK_WDTRST2"
$PN"R20"0;
"GPIOJ5_VGAVS"
$PN"R4"45;
"GPIOJ6_DDCCLK"
$PN"R3"41;
"GPIOJ7_DDCDAT"
$PN"T3"42;
"FWSPICK"
$PN"AA18"43;
"FWSPIMOSI"
$PN"U17"32;
"GPIOJ4_VGAHS"
$PN"N5"46;
"HBLED# \B"
$PN"Y18"0;
"MALERT# \B"
$PN"U16"26;
"MRESET# \B"
$PN"AB17"27;
"GPIOR0_FWSPICS1# \B"
$PN"AA19"17;
"GPIOR1_FWSPICS2# \B"
$PN"T19"24;
"GPIOR2_SPI2CS0# \B"
$PN"T17"18;
"GPIOR5_SPI2MISO"
$PN"V19"21;
"GPIOQ7_PEWAKE# \B"
$PN"N20"22;
"GPIOQ6_OSCCLK"
$PN"B10"23;
"EXTRST# \B"
$PN"V18"0;
"ENTEST"
$PN"K3"16;
"GPIOAC7_ESPIRST#_LPCRST# \B"
$PN"G22"31;
%"RES"
"1","(-6950,3900)","0","mstr_discrete","I26";
;
CDS_SEC"1"
$SEC"1"
CDS_LOCATION"R25W83"
MATERIAL"CHIP"
BOM_COST"MIO_USB"
ROOM"USB"
PART_NUMBER"G21497-005"
WATTAGE"1/16W"
CDS_LIB"mstr_discrete"
PACK_TYPE"0402"
TOLERANCE"5%"
VALUE"0.0"
LOCATION"R25W83";
"B"
$PN"2"9;
"A"
$PN"1"50;
%"RES"
"1","(-6950,3825)","0","mstr_discrete","I27";
;
CDS_SEC"1"
$SEC"1"
CDS_LOCATION"R25W84"
MATERIAL"CHIP"
CDS_LIB"mstr_discrete"
WATTAGE"1/16W"
PART_NUMBER"G21497-005"
ROOM"USB"
BOM_COST"MIO_USB"
PACK_TYPE"0402"
LOCATION"R25W84"
VALUE"0.0"
TOLERANCE"5%";
"B"
$PN"2"9;
"A"
$PN"1"51;
%"RES"
"2","(-1175,4150)","1","mstr_discrete","I35";
;
CDS_SEC"1"
$SEC"1"
CDS_LOCATION"R1T25"
ROOM"BMC"
BOM_COST"SM_CONTROLLER"
CDS_LIB"mstr_discrete"
PART_NUMBER"G21796-345"
PACK_TYPE"0402"
LOCATION"R1T25"
MATERIAL"CHIP"
VALUE"8.2K"
TOLERANCE"1%"
WATTAGE"1/16W";
"A"
$PN"1"78;
"B"
$PN"2"2;
%"GND"
"1","(-275,4200)","1","mstr_symbols","I36";
;
SIZE"1B"
CDS_LIB"mstr_symbols"
VOLTAGE"0.0V"
BODY_TYPE"PLUMBING"
HDL_POWER"GND";
"A\NAC"2;
%"RES"
"2","(-725,4200)","1","mstr_discrete","I37";
;
CDS_LOCATION"R1T26"
BOM_COST"SM_CONTROLLER"
ROOM"BMC"
$SEC"1"
CDS_SEC"1"
CDS_LIB"mstr_discrete"
PACK_TYPE"0402"
PART_NUMBER"G21796-345"
MATERIAL"CHIP"
TOLERANCE"1%"
VALUE"8.2K"
LOCATION"R1T26"
WATTAGE"1/16W";
"A"
$PN"1"75;
"B"
$PN"2"2;
%"RES"
"2","(-1750,4725)","0","mstr_discrete","I51";
;
CDS_LIB"mstr_discrete"
CDS_LOCATION"R1U52"
ROOM"BMC"
$SEC"1"
CDS_SEC"1"
BOM_COST"SM_CONTROLLER"
VALUE"1.5K"
LOCATION"R1U52"
PART_NUMBER"G21796-003"
PACK_TYPE"0402"
MATERIAL"CHIP"
WATTAGE"1/16W"
TOLERANCE"1%";
"A"
$PN"1"3;
"B"
$PN"2"74;
%"P3V3_STBY"
"1","(-1750,4900)","0","mstr_symbols","I52";
;
SIZE"1B"
CDS_LIB"mstr_symbols"
VOLTAGE"3.3V"
BODY_TYPE"PLUMBING"
HDL_POWER"P3V3_STBY";
"G\NAC"3;
%"RES"
"1","(-1275,1525)","0","mstr_discrete","I64";
;
CDS_LOCATION"R25W70"
CDS_LIB"mstr_discrete"
ROOM"BMC"
BOM_COST"SM_CONTROLLER"
SEC_TYPE"0402"
SEC"1"
CDS_SEC"1"
WATTAGE"1/16W"
MATERIAL"CHIP"
PART_NUMBER"G21796-074"
PACK_TYPE"0402"
LOCATION"R25W70"
TOLERANCE"1%"
VALUE"33.2";
"B"
$PN"2"25;
"A"
$PN"1"23;
%"RES"
"2","(-1800,1100)","0","mstr_discrete","I65";
;
CDS_LOCATION"R25W63"
CDS_SEC"1"
CDS_LIB"mstr_discrete"
SEC"1"
SEC_TYPE"0402"
BOM_COST"SM_CONTROLLER"
ROOM"BMC"
WATTAGE"1/16W"
PART_NUMBER"G21796-010"
LOCATION"R25W63"
VALUE"100.0K"
TOLERANCE"1%"
MATERIAL"CHIP"
PACK_TYPE"0402";
"A"
$PN"1"22;
"B"
$PN"2"4;
%"GND"
"1","(-1800,825)","0","mstr_symbols","I66";
;
CDS_LIB"mstr_symbols"
VOLTAGE"0.0V"
SIZE"1B"
BODY_TYPE"PLUMBING"
HDL_POWER"GND";
"A\NAC"4;
%"RES"
"1","(-6225,2350)","0","mstr_discrete","I67";
;
CDS_SEC"1"
CDS_LOCATION"R25W81"
WATTAGE"1/16W"
CDS_LIB"mstr_discrete"
PART_NUMBER"G21796-074"
SEC_TYPE"0402"
SEC"1"
PACK_TYPE"0402"
ROOM"BMC"
BOM_COST"SM_CONTROLLER"
LOCATION"R25W81"
VALUE"33.2"
MATERIAL"CHIP"
TOLERANCE"1%";
"B"
$PN"2"43;
"A"
$PN"1"59;
%"RES"
"1","(-6300,2500)","0","mstr_discrete","I68";
;
CDS_SEC"1"
CDS_LOCATION"R25W82"
WATTAGE"1/16W"
CDS_LIB"mstr_discrete"
PART_NUMBER"G21796-074"
ROOM"BMC"
BOM_COST"SM_CONTROLLER"
SEC_TYPE"0402"
SEC"1"
PACK_TYPE"0402"
TOLERANCE"1%"
LOCATION"R25W82"
MATERIAL"CHIP"
VALUE"33.2";
"B"
$PN"2"32;
"A"
$PN"1"57;
%"RES"
"1","(-6550,2400)","0","mstr_discrete","I69";
;
CDS_SEC"1"
CDS_LOCATION"R25W78"
WATTAGE"1/16W"
CDS_LIB"mstr_discrete"
PART_NUMBER"G21796-250"
SEC_TYPE"0402"
SEC"1"
PACK_TYPE"0402"
ROOM"BMC"
BOM_COST"SM_CONTROLLER"
VALUE"22.1"
LOCATION"R25W78"
TOLERANCE"1.0%"
MATERIAL"CHIP";
"B"
$PN"2"44;
"A"
$PN"1"71;
%"RES"
"1","(-6425,1750)","0","mstr_discrete","I70";
;
CDS_LOCATION"R25W74"
CDS_SEC"1"
CDS_LIB"mstr_discrete"
ROOM"BMC"
SEC_TYPE"0402"
SEC"1"
BOM_COST"SM_CONTROLLER"
MATERIAL"CHIP"
TOLERANCE"5%"
WATTAGE"1/16W"
PART_NUMBER"G21497-005"
PACK_TYPE"0402"
LOCATION"R25W74"
VALUE"0.0";
"B"
$PN"2"31;
"A"
$PN"1"73;
%"RES"
"1","(-6425,1600)","0","mstr_discrete","I71";
;
CDS_LOCATION"R25W72"
TOLERANCE"1%"
WATTAGE"1/16W"
MATERIAL"CHIP"
BOM_COST"SM_CONTROLLER"
SEC_TYPE"0402"
SEC"1"
ROOM"BMC"
CDS_LIB"mstr_discrete"
CDS_SEC"1"
PART_NUMBER"G21796-074"
PACK_TYPE"0402"
VALUE"33.2"
LOCATION"R25W72";
"B"
$PN"2"29;
"A"
$PN"1"72;
%"RES"
"1","(-6425,1500)","0","mstr_discrete","I72";
;
CDS_SEC"1"
$SEC"1"
CDS_LOCATION"R25W71"
ROOM"BMC"
BOM_COST"SM_CONTROLLER"
CDS_LIB"mstr_discrete"
PART_NUMBER"G21796-074"
MATERIAL"CHIP"
TOLERANCE"1%"
WATTAGE"1/16W"
VALUE"33.2"
LOCATION"R25W71"
PACK_TYPE"0402";
"B"
$PN"2"28;
"A"
$PN"1"69;
%"RES"
"1","(-6425,1675)","0","mstr_discrete","I73";
;
CDS_LOCATION"R25W73"
WATTAGE"1/16W"
SEC_TYPE"0402"
BOM_COST"SM_CONTROLLER"
SEC"1"
ROOM"BMC"
CDS_LIB"mstr_discrete"
CDS_SEC"1"
PART_NUMBER"G21796-074"
MATERIAL"CHIP"
TOLERANCE"1%"
LOCATION"R25W73"
VALUE"33.2"
PACK_TYPE"0402";
"B"
$PN"2"30;
"A"
$PN"1"70;
%"RES"
"1","(-6500,1350)","0","mstr_discrete","I74";
;
CDS_SEC"1"
$SEC"1"
CDS_LOCATION"R3N24"
CDS_LIB"mstr_discrete"
BOM_COST"SB"
ROOM"BMC"
MATERIAL"CHIP"
PART_NUMBER"G21796-074"
TOLERANCE"1%"
WATTAGE"1/16W"
LOCATION"R3N24"
VALUE"33.2"
PACK_TYPE"0402";
"B"
$PN"2"40;
"A"
$PN"1"66;
%"RES"
"1","(-6500,1250)","0","mstr_discrete","I75";
;
CDS_SEC"1"
$SEC"1"
CDS_LOCATION"R3N26"
WATTAGE"1/16W"
TOLERANCE"1%"
PART_NUMBER"G21796-074"
CDS_LIB"mstr_discrete"
BOM_COST"SB"
ROOM"BMC"
MATERIAL"CHIP"
PACK_TYPE"0402"
LOCATION"R3N26"
VALUE"33.2";
"B"
$PN"2"39;
"A"
$PN"1"68;
%"RES"
"2","(-5800,800)","0","mstr_discrete","I76";
;
CDS_LOCATION"R25W66"
CDS_LIB"mstr_discrete"
ROOM"BMC"
$SEC"1"
CDS_SEC"1"
LOCATION"R25W66"
PACK_TYPE"0402"
MATERIAL"CHIP"
VALUE"100.0K"
WATTAGE"1/16W"
PART_NUMBER"G21796-010"
TOLERANCE"1%";
"A"
$PN"1"28;
"B"
$PN"2"5;
%"GND"
"1","(-5800,450)","0","mstr_symbols","I77";
;
SIZE"1B"
CDS_LIB"mstr_symbols"
VOLTAGE"0.0V"
BODY_TYPE"PLUMBING"
HDL_POWER"GND";
"A\NAC"5;
%"RES"
"1","(-6725,2650)","0","mstr_discrete","I78";
;
CDS_SEC"1"
SEC"1"
SEC_TYPE"0402"
ROOM"BMC"
BOM_COST"SM_CONTROLLER"
CDS_LIB"mstr_discrete"
CDS_LOCATION"R1U7"
MATERIAL"CHIP"
PART_NUMBER"G21796-016"
WATTAGE"1/16W"
VALUE"10.0K"
LOCATION"R1U7"
TOLERANCE"1%"
PACK_TYPE"0402";
"B"
$PN"2"16;
"A"
$PN"1"6;
%"GND"
"1","(-7050,2650)","5","mstr_symbols","I79";
;
CDS_LIB"mstr_symbols"
SIZE"1B"
VOLTAGE"0.0V"
BODY_TYPE"PLUMBING"
HDL_POWER"GND";
"A\NAC"6;
%"RES"
"1","(-6850,1400)","0","mstr_discrete","I84";
;
CDS_SEC"1"
$SEC"1"
CDS_LOCATION"R25W68"
TOLERANCE"1%"
WATTAGE"1/16W"
CDS_LIB"mstr_discrete"
BOM_COST"SB"
ROOM"BMC"
MATERIAL"CHIP"
PART_NUMBER"G21796-074"
PACK_TYPE"0402"
LOCATION"R25W68"
VALUE"33.2";
"B"
$PN"2"82;
"A"
$PN"1"65;
%"RES"
"1","(-6850,1300)","0","mstr_discrete","I85";
;
CDS_SEC"1"
$SEC"1"
CDS_LOCATION"R25W69"
WATTAGE"1/16W"
TOLERANCE"1%"
PART_NUMBER"G21796-074"
MATERIAL"CHIP"
ROOM"BMC"
BOM_COST"SB"
CDS_LIB"mstr_discrete"
PACK_TYPE"0402"
LOCATION"R25W69"
VALUE"33.2";
"B"
$PN"2"81;
"A"
$PN"1"67;
%"TAP"
"1","(-7250,1400)","2","mstr_standard","I90";
;
CDS_LIB"mstr_standard"
BODY_TYPE"PLUMBING"
HDL_TAP"TRUE";
"B \NAC \NWC"1;
"S \NAC"
BN"3"65;
%"TAP"
"1","(-7250,1250)","2","mstr_standard","I91";
;
CDS_LIB"mstr_standard"
BODY_TYPE"PLUMBING"
HDL_TAP"TRUE";
"B \NAC \NWC"1;
"S \NAC"
BN"0"68;
%"TAP"
"1","(-7250,1300)","2","mstr_standard","I92";
;
CDS_LIB"mstr_standard"
BODY_TYPE"PLUMBING"
HDL_TAP"TRUE";
"B \NAC \NWC"1;
"S \NAC"
BN"1"67;
%"TAP"
"1","(-7250,1350)","2","mstr_standard","I93";
;
CDS_LIB"mstr_standard"
BODY_TYPE"PLUMBING"
HDL_TAP"TRUE";
"B \NAC \NWC"1;
"S \NAC"
BN"2"66;
%"RES"
"1","(-6625,3950)","0","mstr_discrete","I96";
;
CDS_LOCATION"R2T41"
CDS_LIB"mstr_discrete"
ROOM"BMC"
BOM_COST"SM_CONTROLLER"
SEC_TYPE"0402"
SEC"1"
CDS_SEC"1"
MATERIAL"CHIP"
PACK_TYPE"0402"
PART_NUMBER"G21796-250"
VALUE"22.1"
LOCATION"R2T41"
WATTAGE"1/16W"
TOLERANCE"1.0%";
"B"
$PN"2"10;
"A"
$PN"1"38;
END.
